(kicad_pcb
	(version 20260206)
	(generator "pcbnew")
	(generator_version "10.0")
	(general
		(thickness 1.6)
		(legacy_teardrops no)
	)
	(paper "A4")
	(title_block
		(title "netronome-mezz — pcbd0082-001_rev01_jul9_a.brd")
		(comment 1 "Open CloudServer (Microsoft) / footprints 289-296 of 714")
	)
	(layers
		(0 "F.Cu" signal "TOP")
		(4 "In1.Cu" signal "02_GND")
		(6 "In2.Cu" signal "03_SIG")
		(8 "In3.Cu" signal "04_SIG")
		(10 "In4.Cu" signal "05_GND")
		(12 "In5.Cu" signal "06_PWR1")
		(14 "In6.Cu" signal "07_SIG")
		(16 "In7.Cu" signal "08_SIG")
		(18 "In8.Cu" signal "09_GND")
		(2 "B.Cu" signal "BOTTOM")
		(9 "F.Adhes" user "F.Adhesive")
		(11 "B.Adhes" user "B.Adhesive")
		(13 "F.Paste" user "Package Geometry/Pastemask Top")
		(15 "B.Paste" user "Package Geometry/Pastemask Bottom")
		(5 "F.SilkS" user "Ref Des/Silkscreen Top")
		(7 "B.SilkS" user "Ref Des/Silkscreen Bottom")
		(1 "F.Mask" user "Board Geometry/Soldermask Top")
		(3 "B.Mask" user "Board Geometry/Soldermask Bottom")
		(17 "Dwgs.User" user "User.Drawings")
		(19 "Cmts.User" user "User.Comments")
		(21 "Eco1.User" user "User.Eco1")
		(23 "Eco2.User" user "User.Eco2")
		(25 "Edge.Cuts" user "Board Geometry/Outline")
		(27 "Margin" user)
		(31 "F.CrtYd" user "Package Geometry/Place Bound Top")
		(29 "B.CrtYd" user "Package Geometry/Place Bound Bottom")
		(35 "F.Fab" user "Ref Des/Assembly Top")
		(33 "B.Fab" user "Ref Des/Assembly Bottom")
		(45 "User.4" user "COMPVAL_TYPE_BOTTOM")
	)
	(footprint ""
		(layer "F.Cu")
		(at 83.312 37.973)
		(property "Reference" "R107"
			(at 0 0 0)
			(layer "F.SilkS")
			(hide yes)
			(effects
				(font
					(size 1.27 1.27)
				)
			)
		)
		(property "Value" "40.2K"
			(at -0.148158 1.3462 90)
			(unlocked yes)
			(layer "F.Fab")
			(hide yes)
			(effects
				(font
					(size 1.27 0.9652)
					(thickness 0.000001)
				)
				(justify left)
			)
		)
		(property "Device Type" "REST0171"
			(at -0.148158 1.3462 90)
			(unlocked yes)
			(layer "F.Fab")
			(hide yes)
			(effects
				(font
					(size 1.27 0.9652)
					(thickness 0.000001)
				)
				(justify left)
			)
		)
		(duplicate_pad_numbers_are_jumpers no)
		(fp_poly
			(pts
				(xy 0.635 1.0668) (xy 0.635 -1.0668) (xy -0.635 -1.0668) (xy -0.635 1.0668)
			)
			(stroke
				(width 0)
				(type default)
			)
			(fill no)
			(layer "F.CrtYd")
		)
		(fp_line
			(start -0.254 -0.508)
			(end 0.254 -0.508)
			(stroke
				(width 0.0254)
				(type default)
			)
			(layer "F.Fab")
		)
		(fp_line
			(start -0.254 0.508)
			(end -0.254 -0.508)
			(stroke
				(width 0.0254)
				(type default)
			)
			(layer "F.Fab")
		)
		(fp_line
			(start 0.254 -0.508)
			(end 0.254 0.508)
			(stroke
				(width 0.0254)
				(type default)
			)
			(layer "F.Fab")
		)
		(fp_line
			(start 0.254 0.508)
			(end -0.254 0.508)
			(stroke
				(width 0.0254)
				(type default)
			)
			(layer "F.Fab")
		)
		(pad "1" smd rect
			(at 0 -0.4191)
			(size 0.508 0.5334)
			(layers "F.Cu" "F.Mask" "F.Paste")
			(net "GND")
		)
		(pad "2" smd rect
			(at 0 0.4191)
			(size 0.508 0.5334)
			(layers "F.Cu" "F.Mask" "F.Paste")
			(net "11N2140")
		)
		(zone
			(layer "F.Cu")
			(hatch none 0.5)
			(connect_pads
				(clearance 0)
			)
			(min_thickness 0.25)
			(keepout
				(tracks not_allowed)
				(vias allowed)
				(pads allowed)
				(copperpour not_allowed)
				(footprints allowed)
			)
			(placement
				(enabled no)
				(sheetname "")
			)
			(fill
				(thermal_gap 0.5)
				(thermal_bridge_width 0.5)
				(island_removal_mode 0)
			)
			(polygon
				(pts
					(xy 83.3374 37.9476) (xy 83.3374 37.9984) (xy 83.2866 37.9984) (xy 83.2866 37.9476)
				)
			)
		)
	)
	(footprint ""
		(layer "F.Cu")
		(at 4.191 34.163 180)
		(property "Reference" "R98"
			(at 0 0 180)
			(layer "F.SilkS")
			(hide yes)
			(effects
				(font
					(size 1.27 1.27)
				)
			)
		)
		(property "Value" "4.75K"
			(at -0.148158 1.3462 270)
			(unlocked yes)
			(layer "F.Fab")
			(hide yes)
			(effects
				(font
					(size 1.27 0.9652)
					(thickness 0.000001)
				)
				(justify left)
			)
		)
		(property "Device Type" "REST4024"
			(at -0.148158 1.3462 270)
			(unlocked yes)
			(layer "F.Fab")
			(hide yes)
			(effects
				(font
					(size 1.27 0.9652)
					(thickness 0.000001)
				)
				(justify left)
			)
		)
		(duplicate_pad_numbers_are_jumpers no)
		(fp_poly
			(pts
				(xy 0.635 1.0668) (xy 0.635 -1.0668) (xy -0.635 -1.0668) (xy -0.635 1.0668)
			)
			(stroke
				(width 0)
				(type default)
			)
			(fill no)
			(layer "F.CrtYd")
		)
		(fp_line
			(start 0.254 0.508)
			(end -0.254 0.508)
			(stroke
				(width 0.0254)
				(type default)
			)
			(layer "F.Fab")
		)
		(fp_line
			(start 0.254 -0.508)
			(end 0.254 0.508)
			(stroke
				(width 0.0254)
				(type default)
			)
			(layer "F.Fab")
		)
		(fp_line
			(start -0.254 0.508)
			(end -0.254 -0.508)
			(stroke
				(width 0.0254)
				(type default)
			)
			(layer "F.Fab")
		)
		(fp_line
			(start -0.254 -0.508)
			(end 0.254 -0.508)
			(stroke
				(width 0.0254)
				(type default)
			)
			(layer "F.Fab")
		)
		(pad "1" smd rect
			(at 0 -0.4191 180)
			(size 0.508 0.5334)
			(layers "F.Cu" "F.Mask" "F.Paste")
			(net "11N1979")
		)
		(pad "2" smd rect
			(at 0 0.4191 180)
			(size 0.508 0.5334)
			(layers "F.Cu" "F.Mask" "F.Paste")
			(net "VDD_5.0V")
		)
		(zone
			(layer "F.Cu")
			(hatch none 0.5)
			(connect_pads
				(clearance 0)
			)
			(min_thickness 0.25)
			(keepout
				(tracks not_allowed)
				(vias allowed)
				(pads allowed)
				(copperpour not_allowed)
				(footprints allowed)
			)
			(placement
				(enabled no)
				(sheetname "")
			)
			(fill
				(thermal_gap 0.5)
				(thermal_bridge_width 0.5)
				(island_removal_mode 0)
			)
			(polygon
				(pts
					(xy 4.1656 34.1884) (xy 4.1656 34.1376) (xy 4.2164 34.1376) (xy 4.2164 34.1884)
				)
			)
		)
	)
	(footprint ""
		(layer "F.Cu")
		(at 75.057 20.574 90)
		(property "Reference" "C266"
			(at 0.73533 -1.778 0)
			(unlocked yes)
			(layer "F.SilkS")
			(effects
				(font
					(size 0.7874 0.5842)
					(thickness 0.127)
				)
				(justify left)
			)
		)
		(property "Value" "1UF"
			(at -0.091846 0.2921 180)
			(unlocked yes)
			(layer "F.Fab")
			(hide yes)
			(effects
				(font
					(size 0.7874 0.5842)
					(thickness 0.2032)
				)
				(justify left)
			)
		)
		(property "Device Type" "CAPC0028"
			(at -0.091846 0.2921 180)
			(unlocked yes)
			(layer "F.Fab")
			(hide yes)
			(effects
				(font
					(size 0.7874 0.5842)
					(thickness 0.2032)
				)
				(justify left)
			)
		)
		(duplicate_pad_numbers_are_jumpers no)
		(fp_poly
			(pts
				(xy 0.635 1.0668) (xy 0.635 -1.0668) (xy -0.635 -1.0668) (xy -0.635 1.0668)
			)
			(stroke
				(width 0)
				(type default)
			)
			(fill no)
			(layer "F.CrtYd")
		)
		(fp_line
			(start 0.254 -0.508)
			(end 0.254 0.508)
			(stroke
				(width 0.0254)
				(type default)
			)
			(layer "F.Fab")
		)
		(fp_line
			(start -0.254 -0.508)
			(end 0.254 -0.508)
			(stroke
				(width 0.0254)
				(type default)
			)
			(layer "F.Fab")
		)
		(fp_line
			(start 0.254 0.508)
			(end -0.254 0.508)
			(stroke
				(width 0.0254)
				(type default)
			)
			(layer "F.Fab")
		)
		(fp_line
			(start -0.254 0.508)
			(end -0.254 -0.508)
			(stroke
				(width 0.0254)
				(type default)
			)
			(layer "F.Fab")
		)
		(pad "1" smd rect
			(at 0 -0.4191 90)
			(size 0.508 0.5334)
			(layers "F.Cu" "F.Mask" "F.Paste")
			(net "DDR_VDDQ")
		)
		(pad "2" smd rect
			(at 0 0.4191 90)
			(size 0.508 0.5334)
			(layers "F.Cu" "F.Mask" "F.Paste")
			(net "GND")
		)
		(zone
			(layer "F.Cu")
			(hatch none 0.5)
			(connect_pads
				(clearance 0)
			)
			(min_thickness 0.25)
			(keepout
				(tracks not_allowed)
				(vias allowed)
				(pads allowed)
				(copperpour not_allowed)
				(footprints allowed)
			)
			(placement
				(enabled no)
				(sheetname "")
			)
			(fill
				(thermal_gap 0.5)
				(thermal_bridge_width 0.5)
				(island_removal_mode 0)
			)
			(polygon
				(pts
					(xy 75.0316 20.5486) (xy 75.0824 20.5486) (xy 75.0824 20.5994) (xy 75.0316 20.5994)
				)
			)
		)
	)
	(footprint ""
		(layer "F.Cu")
		(at 29.591 44.323 180)
		(property "Reference" "R328"
			(at 0 0 180)
			(layer "F.SilkS")
			(hide yes)
			(effects
				(font
					(size 1.27 1.27)
				)
			)
		)
		(property "Value" "19.1K"
			(at -0.148158 1.3462 270)
			(unlocked yes)
			(layer "F.Fab")
			(hide yes)
			(effects
				(font
					(size 1.27 0.9652)
					(thickness 0.000001)
				)
				(justify left)
			)
		)
		(property "Device Type" "REST0018"
			(at -0.148158 1.3462 270)
			(unlocked yes)
			(layer "F.Fab")
			(hide yes)
			(effects
				(font
					(size 1.27 0.9652)
					(thickness 0.000001)
				)
				(justify left)
			)
		)
		(duplicate_pad_numbers_are_jumpers no)
		(fp_poly
			(pts
				(xy 0.635 1.0668) (xy 0.635 -1.0668) (xy -0.635 -1.0668) (xy -0.635 1.0668)
			)
			(stroke
				(width 0)
				(type default)
			)
			(fill no)
			(layer "F.CrtYd")
		)
		(fp_line
			(start 0.254 0.508)
			(end -0.254 0.508)
			(stroke
				(width 0.0254)
				(type default)
			)
			(layer "F.Fab")
		)
		(fp_line
			(start 0.254 -0.508)
			(end 0.254 0.508)
			(stroke
				(width 0.0254)
				(type default)
			)
			(layer "F.Fab")
		)
		(fp_line
			(start -0.254 0.508)
			(end -0.254 -0.508)
			(stroke
				(width 0.0254)
				(type default)
			)
			(layer "F.Fab")
		)
		(fp_line
			(start -0.254 -0.508)
			(end 0.254 -0.508)
			(stroke
				(width 0.0254)
				(type default)
			)
			(layer "F.Fab")
		)
		(pad "1" smd rect
			(at 0 -0.4191 180)
			(size 0.508 0.5334)
			(layers "F.Cu" "F.Mask" "F.Paste")
			(net "10N2386")
		)
		(pad "2" smd rect
			(at 0 0.4191 180)
			(size 0.508 0.5334)
			(layers "F.Cu" "F.Mask" "F.Paste")
			(net "10N2504")
		)
		(zone
			(layer "F.Cu")
			(hatch none 0.5)
			(connect_pads
				(clearance 0)
			)
			(min_thickness 0.25)
			(keepout
				(tracks not_allowed)
				(vias allowed)
				(pads allowed)
				(copperpour not_allowed)
				(footprints allowed)
			)
			(placement
				(enabled no)
				(sheetname "")
			)
			(fill
				(thermal_gap 0.5)
				(thermal_bridge_width 0.5)
				(island_removal_mode 0)
			)
			(polygon
				(pts
					(xy 29.5656 44.3484) (xy 29.5656 44.2976) (xy 29.6164 44.2976) (xy 29.6164 44.3484)
				)
			)
		)
	)
	(footprint ""
		(layer "F.Cu")
		(at 22.098 29.337 180)
		(property "Reference" "R72"
			(at 0 0 180)
			(layer "F.SilkS")
			(hide yes)
			(effects
				(font
					(size 1.27 1.27)
				)
			)
		)
		(property "Value" "4.75K"
			(at -0.148158 1.3462 270)
			(unlocked yes)
			(layer "F.Fab")
			(hide yes)
			(effects
				(font
					(size 1.27 0.9652)
					(thickness 0.000001)
				)
				(justify left)
			)
		)
		(property "Device Type" "REST4024"
			(at -0.148158 1.3462 270)
			(unlocked yes)
			(layer "F.Fab")
			(hide yes)
			(effects
				(font
					(size 1.27 0.9652)
					(thickness 0.000001)
				)
				(justify left)
			)
		)
		(duplicate_pad_numbers_are_jumpers no)
		(fp_poly
			(pts
				(xy 0.635 1.0668) (xy 0.635 -1.0668) (xy -0.635 -1.0668) (xy -0.635 1.0668)
			)
			(stroke
				(width 0)
				(type default)
			)
			(fill no)
			(layer "F.CrtYd")
		)
		(fp_line
			(start 0.254 0.508)
			(end -0.254 0.508)
			(stroke
				(width 0.0254)
				(type default)
			)
			(layer "F.Fab")
		)
		(fp_line
			(start 0.254 -0.508)
			(end 0.254 0.508)
			(stroke
				(width 0.0254)
				(type default)
			)
			(layer "F.Fab")
		)
		(fp_line
			(start -0.254 0.508)
			(end -0.254 -0.508)
			(stroke
				(width 0.0254)
				(type default)
			)
			(layer "F.Fab")
		)
		(fp_line
			(start -0.254 -0.508)
			(end 0.254 -0.508)
			(stroke
				(width 0.0254)
				(type default)
			)
			(layer "F.Fab")
		)
		(pad "1" smd rect
			(at 0 -0.4191 180)
			(size 0.508 0.5334)
			(layers "F.Cu" "F.Mask" "F.Paste")
			(net "CPLD_PGRM_JTAG_TCK")
		)
		(pad "2" smd rect
			(at 0 0.4191 180)
			(size 0.508 0.5334)
			(layers "F.Cu" "F.Mask" "F.Paste")
			(net "GND")
		)
		(zone
			(layer "F.Cu")
			(hatch none 0.5)
			(connect_pads
				(clearance 0)
			)
			(min_thickness 0.25)
			(keepout
				(tracks not_allowed)
				(vias allowed)
				(pads allowed)
				(copperpour not_allowed)
				(footprints allowed)
			)
			(placement
				(enabled no)
				(sheetname "")
			)
			(fill
				(thermal_gap 0.5)
				(thermal_bridge_width 0.5)
				(island_removal_mode 0)
			)
			(polygon
				(pts
					(xy 22.0726 29.3624) (xy 22.0726 29.3116) (xy 22.1234 29.3116) (xy 22.1234 29.3624)
				)
			)
		)
	)
	(footprint ""
		(layer "F.Cu")
		(at 52.07 41.5417 90)
		(property "Reference" "L18"
			(at 4.81203 -6.731 0)
			(unlocked yes)
			(layer "F.SilkS")
			(effects
				(font
					(size 0.7874 0.5842)
					(thickness 0.127)
				)
				(justify left)
			)
		)
		(property "Value" "300NH"
			(at -0.4826 1.121918 90)
			(unlocked yes)
			(layer "F.Fab")
			(hide yes)
			(effects
				(font
					(size 1.27 0.9652)
					(thickness 0.000001)
				)
				(justify left)
			)
		)
		(property "Device Type" "INDS0042"
			(at -0.4826 1.121918 90)
			(unlocked yes)
			(layer "F.Fab")
			(hide yes)
			(effects
				(font
					(size 1.27 0.9652)
					(thickness 0.000001)
				)
				(justify left)
			)
		)
		(duplicate_pad_numbers_are_jumpers no)
		(fp_line
			(start 4.191 -5.842)
			(end 4.191 -1.2954)
			(stroke
				(width 0.2032)
				(type default)
			)
			(layer "F.SilkS")
		)
		(fp_line
			(start 4.191 -5.842)
			(end 4.191 5.842)
			(stroke
				(width 0.2032)
				(type default)
			)
			(layer "F.SilkS")
		)
		(fp_line
			(start 1.5367 -5.842)
			(end 4.191 -5.842)
			(stroke
				(width 0.2032)
				(type default)
			)
			(layer "F.SilkS")
		)
		(fp_line
			(start 1.524 -5.842)
			(end 4.191 -5.842)
			(stroke
				(width 0.2032)
				(type default)
			)
			(layer "F.SilkS")
		)
		(fp_line
			(start -1.524 -5.842)
			(end -4.191 -5.842)
			(stroke
				(width 0.2032)
				(type default)
			)
			(layer "F.SilkS")
		)
		(fp_line
			(start -1.5367 -5.842)
			(end -4.191 -5.842)
			(stroke
				(width 0.2032)
				(type default)
			)
			(layer "F.SilkS")
		)
		(fp_line
			(start -4.191 -5.842)
			(end -4.191 -3.6576)
			(stroke
				(width 0.2032)
				(type default)
			)
			(layer "F.SilkS")
		)
		(fp_line
			(start -4.191 -5.842)
			(end -4.191 5.842)
			(stroke
				(width 0.2032)
				(type default)
			)
			(layer "F.SilkS")
		)
		(fp_line
			(start -4.191 -1.6764)
			(end -4.191 5.842)
			(stroke
				(width 0.2032)
				(type default)
			)
			(layer "F.SilkS")
		)
		(fp_line
			(start 4.191 3.114675)
			(end 4.191 5.842)
			(stroke
				(width 0.2032)
				(type default)
			)
			(layer "F.SilkS")
		)
		(fp_line
			(start 4.191 5.842)
			(end 2.8956 5.842)
			(stroke
				(width 0.2032)
				(type default)
			)
			(layer "F.SilkS")
		)
		(fp_line
			(start 4.191 5.842)
			(end 1.524 5.842)
			(stroke
				(width 0.2032)
				(type default)
			)
			(layer "F.SilkS")
		)
		(fp_line
			(start -4.191 5.842)
			(end -1.524 5.842)
			(stroke
				(width 0.2032)
				(type default)
			)
			(layer "F.SilkS")
		)
		(fp_line
			(start -4.191 5.842)
			(end -2.8702 5.842)
			(stroke
				(width 0.2032)
				(type default)
			)
			(layer "F.SilkS")
		)
		(fp_poly
			(pts
				(xy -4.445 -6.096) (xy -1.778 -6.096) (xy -1.778 -6.35) (xy 1.778 -6.35) (xy 1.778 -6.096) (xy 4.445 -6.096)
				(xy 4.445 6.096) (xy 1.778 6.096) (xy 1.778 6.35) (xy -1.778 6.35) (xy -1.778 6.096) (xy -4.445 6.096)
			)
			(stroke
				(width 0)
				(type default)
			)
			(fill no)
			(layer "F.CrtYd")
		)
		(fp_line
			(start 3.8227 -5.4991)
			(end -3.8227 -5.4991)
			(stroke
				(width 0.2032)
				(type default)
			)
			(layer "F.Fab")
		)
		(fp_line
			(start -3.8227 -5.4991)
			(end -3.8227 5.4991)
			(stroke
				(width 0.2032)
				(type default)
			)
			(layer "F.Fab")
		)
		(fp_line
			(start 3.8227 5.4991)
			(end 3.8227 -5.4991)
			(stroke
				(width 0.2032)
				(type default)
			)
			(layer "F.Fab")
		)
		(fp_line
			(start -3.8227 5.4991)
			(end 3.8227 5.4991)
			(stroke
				(width 0.2032)
				(type default)
			)
			(layer "F.Fab")
		)
		(pad "1" smd rect
			(at 0 -4.1783 90)
			(size 2.3622 3.4036)
			(layers "F.Cu" "F.Mask" "F.Paste")
			(net "L_2_CORE_PHASE")
		)
		(pad "2" smd rect
			(at 0 4.1783 90)
			(size 2.3622 3.4036)
			(layers "F.Cu" "F.Mask" "F.Paste")
			(net "VDD_CORE")
		)
	)
	(footprint ""
		(layer "F.Cu")
		(at 81.915 28.702 180)
		(property "Reference" "R218"
			(at 0 0 180)
			(layer "F.SilkS")
			(hide yes)
			(effects
				(font
					(size 1.27 1.27)
				)
			)
		)
		(property "Value" "39.0"
			(at -0.148158 1.3462 270)
			(unlocked yes)
			(layer "F.Fab")
			(hide yes)
			(effects
				(font
					(size 1.27 0.9652)
					(thickness 0.000001)
				)
				(justify left)
			)
		)
		(property "Device Type" "REST0108"
			(at -0.148158 1.3462 270)
			(unlocked yes)
			(layer "F.Fab")
			(hide yes)
			(effects
				(font
					(size 1.27 0.9652)
					(thickness 0.000001)
				)
				(justify left)
			)
		)
		(duplicate_pad_numbers_are_jumpers no)
		(fp_poly
			(pts
				(xy 0.635 1.0668) (xy 0.635 -1.0668) (xy -0.635 -1.0668) (xy -0.635 1.0668)
			)
			(stroke
				(width 0)
				(type default)
			)
			(fill no)
			(layer "F.CrtYd")
		)
		(fp_line
			(start 0.254 0.508)
			(end -0.254 0.508)
			(stroke
				(width 0.0254)
				(type default)
			)
			(layer "F.Fab")
		)
		(fp_line
			(start 0.254 -0.508)
			(end 0.254 0.508)
			(stroke
				(width 0.0254)
				(type default)
			)
			(layer "F.Fab")
		)
		(fp_line
			(start -0.254 0.508)
			(end -0.254 -0.508)
			(stroke
				(width 0.0254)
				(type default)
			)
			(layer "F.Fab")
		)
		(fp_line
			(start -0.254 -0.508)
			(end 0.254 -0.508)
			(stroke
				(width 0.0254)
				(type default)
			)
			(layer "F.Fab")
		)
		(pad "1" smd rect
			(at 0 -0.4191 180)
			(size 0.508 0.5334)
			(layers "F.Cu" "F.Mask" "F.Paste")
			(net "DDR0_32A_A12")
		)
		(pad "2" smd rect
			(at 0 0.4191 180)
			(size 0.508 0.5334)
			(layers "F.Cu" "F.Mask" "F.Paste")
			(net "DDR_VTT")
		)
		(zone
			(layer "F.Cu")
			(hatch none 0.5)
			(connect_pads
				(clearance 0)
			)
			(min_thickness 0.25)
			(keepout
				(tracks not_allowed)
				(vias allowed)
				(pads allowed)
				(copperpour not_allowed)
				(footprints allowed)
			)
			(placement
				(enabled no)
				(sheetname "")
			)
			(fill
				(thermal_gap 0.5)
				(thermal_bridge_width 0.5)
				(island_removal_mode 0)
			)
			(polygon
				(pts
					(xy 81.8896 28.7274) (xy 81.8896 28.6766) (xy 81.9404 28.6766) (xy 81.9404 28.7274)
				)
			)
		)
	)
	(footprint ""
		(layer "F.Cu")
		(at -1.016 31.369)
		(property "Reference" "TP66"
			(at -0.48133 -1.016 90)
			(unlocked yes)
			(layer "F.SilkS")
			(effects
				(font
					(size 0.7874 0.5842)
					(thickness 0.127)
				)
				(justify left)
			)
		)
		(property "Value" "*"
			(at -0.4826 -0.14732 0)
			(unlocked yes)
			(layer "F.Fab")
			(hide yes)
			(effects
				(font
					(size 1.27 0.9652)
					(thickness 0.000001)
				)
				(justify left)
			)
		)
		(property "Device Type" "TP_SMALL"
			(at -0.4826 -0.14732 0)
			(unlocked yes)
			(layer "F.Fab")
			(hide yes)
			(effects
				(font
					(size 1.27 0.9652)
					(thickness 0.000001)
				)
				(justify left)
			)
		)
		(duplicate_pad_numbers_are_jumpers no)
		(fp_line
			(start -0.8636 -0.8636)
			(end -0.8636 0.8636)
			(stroke
				(width 0.1524)
				(type default)
			)
			(layer "F.SilkS")
		)
		(fp_line
			(start -0.8636 0.8636)
			(end 0.8636 0.8636)
			(stroke
				(width 0.1524)
				(type default)
			)
			(layer "F.SilkS")
		)
		(fp_line
			(start 0.8636 -0.8636)
			(end -0.8636 -0.8636)
			(stroke
				(width 0.1524)
				(type default)
			)
			(layer "F.SilkS")
		)
		(fp_line
			(start 0.8636 0.8636)
			(end 0.8636 -0.8636)
			(stroke
				(width 0.1524)
				(type default)
			)
			(layer "F.SilkS")
		)
		(fp_poly
			(pts
				(xy -0.635 -0.635) (xy -0.635 0.635) (xy 0.635 0.635) (xy 0.635 -0.635)
			)
			(stroke
				(width 0)
				(type default)
			)
			(fill no)
			(layer "F.CrtYd")
		)
		(pad "1" smd rect
			(at 0 0)
			(size 1.27 1.27)
			(layers "F.Cu" "F.Mask" "F.Paste")
			(net "VDD_7401_EN")
		)
	)
)
